(kicad_pcb
	(version 20260206)
	(generator "pcbnew")
	(generator_version "10.0")
	(general
		(thickness 1.6)
		(legacy_teardrops no)
	)
	(paper "A4")
	(title_block
		(title "pdpb — Lightning_PDPB_BRD.brd")
		(comment 1 "Lightning (Wiwynn / Facebook NVMe JBOF) / footprints 836-843 of 1140")
	)
	(layers
		(0 "F.Cu" signal "TOP")
		(4 "In1.Cu" signal "L2GND")
		(6 "In2.Cu" signal "L3")
		(8 "In3.Cu" signal "L4VCC")
		(10 "In4.Cu" signal "L5VCC")
		(12 "In5.Cu" signal "L6")
		(14 "In6.Cu" signal "L7GND")
		(2 "B.Cu" signal "BOTTOM")
		(9 "F.Adhes" user "F.Adhesive")
		(11 "B.Adhes" user "B.Adhesive")
		(13 "F.Paste" user "Package Geometry/Pastemask Top")
		(15 "B.Paste" user "Package Geometry/Pastemask Bottom")
		(5 "F.SilkS" user "Ref Des/Silkscreen Top")
		(7 "B.SilkS" user "Ref Des/Silkscreen Bottom")
		(1 "F.Mask" user "Board Geometry/Soldermask Top")
		(3 "B.Mask" user "Board Geometry/Soldermask Bottom")
		(17 "Dwgs.User" user "User.Drawings")
		(19 "Cmts.User" user "User.Comments")
		(21 "Eco1.User" user "User.Eco1")
		(23 "Eco2.User" user "User.Eco2")
		(25 "Edge.Cuts" user "Board Geometry/Outline")
		(27 "Margin" user)
		(31 "F.CrtYd" user "Package Geometry/Place Bound Top")
		(29 "B.CrtYd" user "Package Geometry/Place Bound Bottom")
		(35 "F.Fab" user "Ref Des/Assembly Top")
		(33 "B.Fab" user "Ref Des/Assembly Bottom")
	)
	(footprint ""
		(layer "F.Cu")
		(at 13.208 -478.155 180)
		(property "Reference" "R411"
			(at 0 0 180)
			(layer "F.SilkS")
			(hide yes)
			(effects
				(font
					(size 1.27 1.27)
				)
			)
		)
		(property "Value" "100R2J-2-GP"
			(at 0.064008 -3.993896 180)
			(unlocked yes)
			(layer "F.Fab")
			(hide yes)
			(effects
				(font
					(size 1.016 1.016)
					(thickness 0.1524)
				)
			)
		)
		(property "Device Type" "R402H14"
			(at 0.064008 -5.517896 180)
			(unlocked yes)
			(layer "F.Fab")
			(hide yes)
			(effects
				(font
					(size 1.016 1.016)
					(thickness 0.1524)
				)
			)
		)
		(duplicate_pad_numbers_are_jumpers no)
		(fp_line
			(start 0.508 -0.9398)
			(end -0.508 -0.9398)
			(stroke
				(width 0.1524)
				(type default)
			)
			(layer "F.SilkS")
		)
		(fp_line
			(start -0.508 -0.9398)
			(end -0.508 0.9398)
			(stroke
				(width 0.1524)
				(type default)
			)
			(layer "F.SilkS")
		)
		(fp_rect
			(start -0.508 0.9398)
			(end 0.508 -0.9398)
			(stroke
				(width 0)
				(type default)
			)
			(fill no)
			(layer "F.CrtYd")
		)
		(fp_rect
			(start -0.508 0.9398)
			(end 0.508 -0.9398)
			(stroke
				(width 0)
				(type default)
			)
			(fill no)
			(layer "F.Fab")
		)
		(pad "1" smd custom
			(at 0 -0.4445 180)
			(size 0.1397 0.1397)
			(layers "F.Cu" "F.Mask" "F.Paste")
			(net "DPB_HW_REVISION")
			(options
				(clearance outline)
				(anchor circle)
			)
			(primitives
				(gr_poly
					(pts
						(arc
							(start -0.1778 -0.2794)
							(mid -0.249642 -0.249642)
							(end -0.2794 -0.1778)
						)
						(arc
							(start -0.2794 0.1778)
							(mid -0.249642 0.249642)
							(end -0.1778 0.2794)
						)
						(arc
							(start 0.1778 0.2794)
							(mid 0.249642 0.249642)
							(end 0.2794 0.1778)
						)
						(arc
							(start 0.2794 -0.1778)
							(mid 0.249642 -0.249642)
							(end 0.1778 -0.2794)
						)
					)
					(width 0)
					(fill yes)
				)
			)
		)
		(pad "2" smd custom
			(at 0 0.4445 180)
			(size 0.1397 0.1397)
			(layers "F.Cu" "F.Mask" "F.Paste")
			(net "GND")
			(options
				(clearance outline)
				(anchor circle)
			)
			(primitives
				(gr_poly
					(pts
						(arc
							(start -0.1778 -0.2794)
							(mid -0.249642 -0.249642)
							(end -0.2794 -0.1778)
						)
						(arc
							(start -0.2794 0.1778)
							(mid -0.249642 0.249642)
							(end -0.1778 0.2794)
						)
						(arc
							(start 0.1778 0.2794)
							(mid 0.249642 0.249642)
							(end 0.2794 0.1778)
						)
						(arc
							(start 0.2794 -0.1778)
							(mid 0.249642 -0.249642)
							(end 0.1778 -0.2794)
						)
					)
					(width 0)
					(fill yes)
				)
			)
		)
	)
	(footprint ""
		(layer "F.Cu")
		(at 23.1648 -87.122)
		(property "Reference" "R560"
			(at 0 0 0)
			(layer "F.SilkS")
			(hide yes)
			(effects
				(font
					(size 1.27 1.27)
				)
			)
		)
		(property "Value" "200KR2F-L-GP"
			(at 0.064008 -3.993896 0)
			(unlocked yes)
			(layer "F.Fab")
			(hide yes)
			(effects
				(font
					(size 1.016 1.016)
					(thickness 0.1524)
				)
			)
		)
		(property "Device Type" "R402H16"
			(at 0.064008 -5.517896 0)
			(unlocked yes)
			(layer "F.Fab")
			(hide yes)
			(effects
				(font
					(size 1.016 1.016)
					(thickness 0.1524)
				)
			)
		)
		(duplicate_pad_numbers_are_jumpers no)
		(fp_line
			(start -0.508 -0.9398)
			(end -0.508 0.9398)
			(stroke
				(width 0.1524)
				(type default)
			)
			(layer "F.SilkS")
		)
		(fp_line
			(start 0.508 -0.9398)
			(end -0.508 -0.9398)
			(stroke
				(width 0.1524)
				(type default)
			)
			(layer "F.SilkS")
		)
		(fp_rect
			(start -0.508 0.9398)
			(end 0.508 -0.9398)
			(stroke
				(width 0)
				(type default)
			)
			(fill no)
			(layer "F.CrtYd")
		)
		(fp_rect
			(start -0.508 0.9398)
			(end 0.508 -0.9398)
			(stroke
				(width 0)
				(type default)
			)
			(fill no)
			(layer "F.Fab")
		)
		(pad "1" smd custom
			(at 0 -0.4445)
			(size 0.1397 0.1397)
			(layers "F.Cu" "F.Mask" "F.Paste")
			(net "SW_SSD9_R")
			(options
				(clearance outline)
				(anchor circle)
			)
			(primitives
				(gr_poly
					(pts
						(arc
							(start -0.1778 -0.2794)
							(mid -0.249642 -0.249642)
							(end -0.2794 -0.1778)
						)
						(arc
							(start -0.2794 0.1778)
							(mid -0.249642 0.249642)
							(end -0.1778 0.2794)
						)
						(arc
							(start 0.1778 0.2794)
							(mid 0.249642 0.249642)
							(end 0.2794 0.1778)
						)
						(arc
							(start 0.2794 -0.1778)
							(mid 0.249642 -0.249642)
							(end 0.1778 -0.2794)
						)
					)
					(width 0)
					(fill yes)
				)
			)
		)
		(pad "2" smd custom
			(at 0 0.4445)
			(size 0.1397 0.1397)
			(layers "F.Cu" "F.Mask" "F.Paste")
			(net "SW_SSD9_N")
			(options
				(clearance outline)
				(anchor circle)
			)
			(primitives
				(gr_poly
					(pts
						(arc
							(start -0.1778 -0.2794)
							(mid -0.249642 -0.249642)
							(end -0.2794 -0.1778)
						)
						(arc
							(start -0.2794 0.1778)
							(mid -0.249642 0.249642)
							(end -0.1778 0.2794)
						)
						(arc
							(start 0.1778 0.2794)
							(mid 0.249642 0.249642)
							(end 0.2794 0.1778)
						)
						(arc
							(start 0.2794 -0.1778)
							(mid 0.249642 -0.249642)
							(end 0.1778 -0.2794)
						)
					)
					(width 0)
					(fill yes)
				)
			)
		)
	)
	(footprint ""
		(layer "F.Cu")
		(at 43.282108 -346.706952 180)
		(property "Reference" "SR1134"
			(at 0 0 180)
			(layer "F.SilkS")
			(hide yes)
			(effects
				(font
					(size 1.27 1.27)
				)
			)
		)
		(property "Value" "4K7R2J-2-GP"
			(at 0.064008 -3.993896 180)
			(unlocked yes)
			(layer "F.Fab")
			(hide yes)
			(effects
				(font
					(size 1.016 1.016)
					(thickness 0.1524)
				)
			)
		)
		(property "Device Type" "R402H16"
			(at 0.064008 -5.517896 180)
			(unlocked yes)
			(layer "F.Fab")
			(hide yes)
			(effects
				(font
					(size 1.016 1.016)
					(thickness 0.1524)
				)
			)
		)
		(duplicate_pad_numbers_are_jumpers no)
		(fp_line
			(start 0.508 -0.9398)
			(end -0.508 -0.9398)
			(stroke
				(width 0.1524)
				(type default)
			)
			(layer "F.SilkS")
		)
		(fp_line
			(start -0.508 -0.9398)
			(end -0.508 0.9398)
			(stroke
				(width 0.1524)
				(type default)
			)
			(layer "F.SilkS")
		)
		(fp_rect
			(start -0.508 0.9398)
			(end 0.508 -0.9398)
			(stroke
				(width 0)
				(type default)
			)
			(fill no)
			(layer "F.CrtYd")
		)
		(fp_rect
			(start -0.508 0.9398)
			(end 0.508 -0.9398)
			(stroke
				(width 0)
				(type default)
			)
			(fill no)
			(layer "F.Fab")
		)
		(pad "1" smd custom
			(at 0 -0.4445 180)
			(size 0.1397 0.1397)
			(layers "F.Cu" "F.Mask" "F.Paste")
			(net "P3V3")
			(options
				(clearance outline)
				(anchor circle)
			)
			(primitives
				(gr_poly
					(pts
						(arc
							(start -0.1778 -0.2794)
							(mid -0.249642 -0.249642)
							(end -0.2794 -0.1778)
						)
						(arc
							(start -0.2794 0.1778)
							(mid -0.249642 0.249642)
							(end -0.1778 0.2794)
						)
						(arc
							(start 0.1778 0.2794)
							(mid 0.249642 0.249642)
							(end 0.2794 0.1778)
						)
						(arc
							(start 0.2794 -0.1778)
							(mid 0.249642 -0.249642)
							(end 0.1778 -0.2794)
						)
					)
					(width 0)
					(fill yes)
				)
			)
		)
		(pad "2" smd custom
			(at 0 0.4445 180)
			(size 0.1397 0.1397)
			(layers "F.Cu" "F.Mask" "F.Paste")
			(net "SSD_ACT_DR6")
			(options
				(clearance outline)
				(anchor circle)
			)
			(primitives
				(gr_poly
					(pts
						(arc
							(start -0.1778 -0.2794)
							(mid -0.249642 -0.249642)
							(end -0.2794 -0.1778)
						)
						(arc
							(start -0.2794 0.1778)
							(mid -0.249642 0.249642)
							(end -0.1778 0.2794)
						)
						(arc
							(start 0.1778 0.2794)
							(mid 0.249642 0.249642)
							(end 0.2794 0.1778)
						)
						(arc
							(start 0.2794 -0.1778)
							(mid 0.249642 -0.249642)
							(end 0.1778 -0.2794)
						)
					)
					(width 0)
					(fill yes)
				)
			)
		)
	)
	(footprint ""
		(layer "F.Cu")
		(at 68.49999 -378.499878)
		(property "Reference" "H3"
			(at 0 0 0)
			(layer "F.SilkS")
			(hide yes)
			(effects
				(font
					(size 1.27 1.27)
				)
			)
		)
		(property "Value" "HOLE315R140-GP"
			(at 0 -7.5692 0)
			(unlocked yes)
			(layer "F.Fab")
			(hide yes)
			(effects
				(font
					(size 1.016 1.016)
					(thickness 0.1524)
				)
			)
		)
		(property "Device Type" "HOLE315R140"
			(at 0 -9.0932 0)
			(unlocked yes)
			(layer "F.Fab")
			(hide yes)
			(effects
				(font
					(size 1.016 1.016)
					(thickness 0.1524)
				)
			)
		)
		(duplicate_pad_numbers_are_jumpers no)
		(fp_poly
			(pts
				(arc
					(start 4.3053 0)
					(mid -4.3053 0)
					(end 4.3053 0)
				)
			)
			(stroke
				(width 0)
				(type default)
			)
			(fill no)
			(layer "F.CrtYd")
		)
		(fp_poly
			(pts
				(arc
					(start 4.3053 0)
					(mid -4.3053 0)
					(end 4.3053 0)
				)
			)
			(stroke
				(width 0)
				(type default)
			)
			(fill no)
			(layer "F.Fab")
		)
		(pad "1" thru_hole circle
			(at 0.00127 0.00127)
			(size 8.001 8.001)
			(drill 3.556)
			(layers "*.Cu" "*.Mask")
			(remove_unused_layers no)
			(net "GND")
			(clearance -1.7145)
			(thermal_gap 0.3048)
			(padstack
				(mode front_inner_back)
				(layer "Inner"
					(shape circle)
					(size 3.9624 3.9624)
					(clearance 0.3048)
				)
				(layer "B.Cu"
					(shape circle)
					(size 8.001 8.001)
					(clearance -1.7145)
				)
			)
		)
	)
	(footprint ""
		(layer "F.Cu")
		(at 102.616 -438.15 90)
		(property "Reference" "R9056"
			(at 0 0 90)
			(layer "F.SilkS")
			(hide yes)
			(effects
				(font
					(size 1.27 1.27)
				)
			)
		)
		(property "Value" "27R2F-GP"
			(at 0.064008 -3.993896 90)
			(unlocked yes)
			(layer "F.Fab")
			(hide yes)
			(effects
				(font
					(size 1.016 1.016)
					(thickness 0.1524)
				)
			)
		)
		(property "Device Type" "R402H16"
			(at 0.064008 -5.517896 90)
			(unlocked yes)
			(layer "F.Fab")
			(hide yes)
			(effects
				(font
					(size 1.016 1.016)
					(thickness 0.1524)
				)
			)
		)
		(duplicate_pad_numbers_are_jumpers no)
		(fp_line
			(start 0.508 -0.9398)
			(end -0.508 -0.9398)
			(stroke
				(width 0.1524)
				(type default)
			)
			(layer "F.SilkS")
		)
		(fp_line
			(start -0.508 -0.9398)
			(end -0.508 0.9398)
			(stroke
				(width 0.1524)
				(type default)
			)
			(layer "F.SilkS")
		)
		(fp_rect
			(start -0.508 0.9398)
			(end 0.508 -0.9398)
			(stroke
				(width 0)
				(type default)
			)
			(fill no)
			(layer "F.CrtYd")
		)
		(fp_rect
			(start -0.508 0.9398)
			(end 0.508 -0.9398)
			(stroke
				(width 0)
				(type default)
			)
			(fill no)
			(layer "F.Fab")
		)
		(pad "1" smd custom
			(at 0 -0.4445 90)
			(size 0.1397 0.1397)
			(layers "F.Cu" "F.Mask" "F.Paste")
			(net "PE_CLK_100M_DR0_1_R_N")
			(options
				(clearance outline)
				(anchor circle)
			)
			(primitives
				(gr_poly
					(pts
						(arc
							(start -0.1778 -0.2794)
							(mid -0.249642 -0.249642)
							(end -0.2794 -0.1778)
						)
						(arc
							(start -0.2794 0.1778)
							(mid -0.249642 0.249642)
							(end -0.1778 0.2794)
						)
						(arc
							(start 0.1778 0.2794)
							(mid 0.249642 0.249642)
							(end 0.2794 0.1778)
						)
						(arc
							(start 0.2794 -0.1778)
							(mid 0.249642 -0.249642)
							(end 0.1778 -0.2794)
						)
					)
					(width 0)
					(fill yes)
				)
			)
		)
		(pad "2" smd custom
			(at 0 0.4445 90)
			(size 0.1397 0.1397)
			(layers "F.Cu" "F.Mask" "F.Paste")
			(net "PE_CLK100M_DR0_1_N")
			(options
				(clearance outline)
				(anchor circle)
			)
			(primitives
				(gr_poly
					(pts
						(arc
							(start -0.1778 -0.2794)
							(mid -0.249642 -0.249642)
							(end -0.2794 -0.1778)
						)
						(arc
							(start -0.2794 0.1778)
							(mid -0.249642 0.249642)
							(end -0.1778 0.2794)
						)
						(arc
							(start 0.1778 0.2794)
							(mid 0.249642 0.249642)
							(end 0.2794 0.1778)
						)
						(arc
							(start 0.2794 -0.1778)
							(mid 0.249642 -0.249642)
							(end 0.1778 -0.2794)
						)
					)
					(width 0)
					(fill yes)
				)
			)
		)
	)
	(footprint ""
		(layer "F.Cu")
		(at 81.661 -359.029 -90)
		(property "Reference" "SR993"
			(at 0 0 270)
			(layer "F.SilkS")
			(hide yes)
			(effects
				(font
					(size 1.27 1.27)
				)
			)
		)
		(property "Value" "2KR2F-3-GP"
			(at 0.064008 -3.993896 270)
			(unlocked yes)
			(layer "F.Fab")
			(hide yes)
			(effects
				(font
					(size 1.016 1.016)
					(thickness 0.1524)
				)
			)
		)
		(property "Device Type" "R402H16"
			(at 0.064008 -5.517896 270)
			(unlocked yes)
			(layer "F.Fab")
			(hide yes)
			(effects
				(font
					(size 1.016 1.016)
					(thickness 0.1524)
				)
			)
		)
		(duplicate_pad_numbers_are_jumpers no)
		(fp_line
			(start -0.508 -0.9398)
			(end -0.508 0.9398)
			(stroke
				(width 0.1524)
				(type default)
			)
			(layer "F.SilkS")
		)
		(fp_line
			(start 0.508 -0.9398)
			(end -0.508 -0.9398)
			(stroke
				(width 0.1524)
				(type default)
			)
			(layer "F.SilkS")
		)
		(fp_rect
			(start -0.508 0.9398)
			(end 0.508 -0.9398)
			(stroke
				(width 0)
				(type default)
			)
			(fill no)
			(layer "F.CrtYd")
		)
		(fp_rect
			(start -0.508 0.9398)
			(end 0.508 -0.9398)
			(stroke
				(width 0)
				(type default)
			)
			(fill no)
			(layer "F.Fab")
		)
		(pad "1" smd custom
			(at 0 -0.4445 270)
			(size 0.1397 0.1397)
			(layers "F.Cu" "F.Mask" "F.Paste")
			(net "P3V3")
			(options
				(clearance outline)
				(anchor circle)
			)
			(primitives
				(gr_poly
					(pts
						(arc
							(start -0.1778 -0.2794)
							(mid -0.249642 -0.249642)
							(end -0.2794 -0.1778)
						)
						(arc
							(start -0.2794 0.1778)
							(mid -0.249642 0.249642)
							(end -0.1778 0.2794)
						)
						(arc
							(start 0.1778 0.2794)
							(mid 0.249642 0.249642)
							(end 0.2794 0.1778)
						)
						(arc
							(start 0.2794 -0.1778)
							(mid 0.249642 -0.249642)
							(end 0.1778 -0.2794)
						)
					)
					(width 0)
					(fill yes)
				)
			)
		)
		(pad "2" smd custom
			(at 0 0.4445 270)
			(size 0.1397 0.1397)
			(layers "F.Cu" "F.Mask" "F.Paste")
			(net "SCL_DR2")
			(options
				(clearance outline)
				(anchor circle)
			)
			(primitives
				(gr_poly
					(pts
						(arc
							(start -0.1778 -0.2794)
							(mid -0.249642 -0.249642)
							(end -0.2794 -0.1778)
						)
						(arc
							(start -0.2794 0.1778)
							(mid -0.249642 0.249642)
							(end -0.1778 0.2794)
						)
						(arc
							(start 0.1778 0.2794)
							(mid 0.249642 0.249642)
							(end 0.2794 0.1778)
						)
						(arc
							(start 0.2794 -0.1778)
							(mid 0.249642 -0.249642)
							(end 0.1778 -0.2794)
						)
					)
					(width 0)
					(fill yes)
				)
			)
		)
	)
	(footprint ""
		(layer "F.Cu")
		(at 96.774 -320.167 90)
		(property "Reference" "R9502"
			(at 0 0 90)
			(layer "F.SilkS")
			(hide yes)
			(effects
				(font
					(size 1.27 1.27)
				)
			)
		)
		(property "Value" "4K7R2J-2-GP"
			(at 0.064008 -3.993896 90)
			(unlocked yes)
			(layer "F.Fab")
			(hide yes)
			(effects
				(font
					(size 1.016 1.016)
					(thickness 0.1524)
				)
			)
		)
		(property "Device Type" "R402H16"
			(at 0.064008 -5.517896 90)
			(unlocked yes)
			(layer "F.Fab")
			(hide yes)
			(effects
				(font
					(size 1.016 1.016)
					(thickness 0.1524)
				)
			)
		)
		(duplicate_pad_numbers_are_jumpers no)
		(fp_line
			(start 0.508 -0.9398)
			(end -0.508 -0.9398)
			(stroke
				(width 0.1524)
				(type default)
			)
			(layer "F.SilkS")
		)
		(fp_line
			(start -0.508 -0.9398)
			(end -0.508 0.9398)
			(stroke
				(width 0.1524)
				(type default)
			)
			(layer "F.SilkS")
		)
		(fp_rect
			(start -0.508 0.9398)
			(end 0.508 -0.9398)
			(stroke
				(width 0)
				(type default)
			)
			(fill no)
			(layer "F.CrtYd")
		)
		(fp_rect
			(start -0.508 0.9398)
			(end 0.508 -0.9398)
			(stroke
				(width 0)
				(type default)
			)
			(fill no)
			(layer "F.Fab")
		)
		(pad "1" smd custom
			(at 0 -0.4445 90)
			(size 0.1397 0.1397)
			(layers "F.Cu" "F.Mask" "F.Paste")
			(net "P3V3")
			(options
				(clearance outline)
				(anchor circle)
			)
			(primitives
				(gr_poly
					(pts
						(arc
							(start -0.1778 -0.2794)
							(mid -0.249642 -0.249642)
							(end -0.2794 -0.1778)
						)
						(arc
							(start -0.2794 0.1778)
							(mid -0.249642 0.249642)
							(end -0.1778 0.2794)
						)
						(arc
							(start 0.1778 0.2794)
							(mid 0.249642 0.249642)
							(end 0.2794 0.1778)
						)
						(arc
							(start 0.2794 -0.1778)
							(mid 0.249642 -0.249642)
							(end 0.1778 -0.2794)
						)
					)
					(width 0)
					(fill yes)
				)
			)
		)
		(pad "2" smd custom
			(at 0 0.4445 90)
			(size 0.1397 0.1397)
			(layers "F.Cu" "F.Mask" "F.Paste")
			(net "SSD6_CLK0_OE_N")
			(options
				(clearance outline)
				(anchor circle)
			)
			(primitives
				(gr_poly
					(pts
						(arc
							(start -0.1778 -0.2794)
							(mid -0.249642 -0.249642)
							(end -0.2794 -0.1778)
						)
						(arc
							(start -0.2794 0.1778)
							(mid -0.249642 0.249642)
							(end -0.1778 0.2794)
						)
						(arc
							(start 0.1778 0.2794)
							(mid 0.249642 0.249642)
							(end 0.2794 0.1778)
						)
						(arc
							(start 0.2794 -0.1778)
							(mid 0.249642 -0.249642)
							(end 0.1778 -0.2794)
						)
					)
					(width 0)
					(fill yes)
				)
			)
		)
	)
	(footprint ""
		(layer "F.Cu")
		(at 37.0332 -189.0014)
		(property "Reference" "PC1218"
			(at 0 0 0)
			(layer "F.SilkS")
			(hide yes)
			(effects
				(font
					(size 1.27 1.27)
				)
			)
		)
		(property "Value" "SCD01U50V2KX-1GP"
			(at 1.1811 -2.7051 0)
			(unlocked yes)
			(layer "F.Fab")
			(hide yes)
			(effects
				(font
					(size 1.016 1.016)
					(thickness 0.1524)
				)
			)
		)
		(property "Device Type" "C402H22"
			(at 1.1811 -4.2291 0)
			(unlocked yes)
			(layer "F.Fab")
			(hide yes)
			(effects
				(font
					(size 1.016 1.016)
					(thickness 0.1524)
				)
			)
		)
		(duplicate_pad_numbers_are_jumpers no)
		(fp_rect
			(start -0.4318 0.9525)
			(end 0.4318 -0.9525)
			(stroke
				(width 0)
				(type default)
			)
			(fill no)
			(layer "F.CrtYd")
		)
		(fp_rect
			(start -0.4318 0.9525)
			(end 0.4318 -0.9525)
			(stroke
				(width 0)
				(type default)
			)
			(fill no)
			(layer "F.Fab")
		)
		(pad "1" smd custom
			(at 0 -0.4445)
			(size 0.1524 0.1524)
			(layers "F.Cu" "F.Mask" "F.Paste")
			(net "P12V_SSD8")
			(options
				(clearance outline)
				(anchor circle)
			)
			(primitives
				(gr_poly
					(pts
						(arc
							(start 0.3048 -0.2032)
							(mid 0.275042 -0.275042)
							(end 0.2032 -0.3048)
						)
						(arc
							(start -0.2032 -0.3048)
							(mid -0.275042 -0.275042)
							(end -0.3048 -0.2032)
						)
						(arc
							(start -0.3048 0.2032)
							(mid -0.275042 0.275042)
							(end -0.2032 0.3048)
						)
						(arc
							(start 0.2032 0.3048)
							(mid 0.275042 0.275042)
							(end 0.3048 0.2032)
						)
					)
					(width 0)
					(fill yes)
				)
			)
		)
		(pad "2" smd custom
			(at 0 0.4445)
			(size 0.1524 0.1524)
			(layers "F.Cu" "F.Mask" "F.Paste")
			(net "GND")
			(options
				(clearance outline)
				(anchor circle)
			)
			(primitives
				(gr_poly
					(pts
						(arc
							(start 0.3048 -0.2032)
							(mid 0.275042 -0.275042)
							(end 0.2032 -0.3048)
						)
						(arc
							(start -0.2032 -0.3048)
							(mid -0.275042 -0.275042)
							(end -0.3048 -0.2032)
						)
						(arc
							(start -0.3048 0.2032)
							(mid -0.275042 0.275042)
							(end -0.2032 0.3048)
						)
						(arc
							(start 0.2032 0.3048)
							(mid 0.275042 0.275042)
							(end 0.3048 0.2032)
						)
					)
					(width 0)
					(fill yes)
				)
			)
		)
	)
)
